(kicad_pcb
	(version 20260206)
	(generator "pcbnew")
	(generator_version "10.0")
	(general
		(thickness 1.6)
		(legacy_teardrops no)
	)
	(paper "A4")
	(title_block
		(title "baseboard — 13948-1b.1110WZS1818.brd")
		(comment 1 "Honey Badger (Wiwynn) / footprints 481-488 of 2523")
	)
	(layers
		(0 "F.Cu" signal "TOP")
		(4 "In1.Cu" signal "L2GND")
		(6 "In2.Cu" signal "L3")
		(8 "In3.Cu" signal "L4VCC")
		(10 "In4.Cu" signal "L5VCC")
		(12 "In5.Cu" signal "L6")
		(14 "In6.Cu" signal "L7GND")
		(2 "B.Cu" signal "BOTTOM")
		(9 "F.Adhes" user "F.Adhesive")
		(11 "B.Adhes" user "B.Adhesive")
		(13 "F.Paste" user "Package Geometry/Pastemask Top")
		(15 "B.Paste" user "Package Geometry/Pastemask Bottom")
		(5 "F.SilkS" user "Ref Des/Silkscreen Top")
		(7 "B.SilkS" user "Ref Des/Silkscreen Bottom")
		(1 "F.Mask" user "Board Geometry/Soldermask Top")
		(3 "B.Mask" user "Board Geometry/Soldermask Bottom")
		(17 "Dwgs.User" user "User.Drawings")
		(19 "Cmts.User" user "User.Comments")
		(21 "Eco1.User" user "User.Eco1")
		(23 "Eco2.User" user "User.Eco2")
		(25 "Edge.Cuts" user "Board Geometry/Outline")
		(27 "Margin" user)
		(31 "F.CrtYd" user "Package Geometry/Place Bound Top")
		(29 "B.CrtYd" user "Package Geometry/Place Bound Bottom")
		(35 "F.Fab" user "Ref Des/Assembly Top")
		(33 "B.Fab" user "Ref Des/Assembly Bottom")
	)
	(footprint ""
		(layer "F.Cu")
		(at 347.599 -96.52 90)
		(property "Reference" "PC16"
			(at 0 0 90)
			(layer "F.SilkS")
			(hide yes)
			(effects
				(font
					(size 1.27 1.27)
				)
			)
		)
		(property "Value" "SC22U10V5MX-GP"
			(at -0.0762 -6.1214 90)
			(unlocked yes)
			(layer "F.Fab")
			(hide yes)
			(effects
				(font
					(size 1.016 1.016)
					(thickness 0.1524)
				)
			)
		)
		(property "Device Type" "C805H56"
			(at -0.0762 -8.1534 90)
			(unlocked yes)
			(layer "F.Fab")
			(hide yes)
			(effects
				(font
					(size 1.016 1.016)
					(thickness 0.1524)
				)
			)
		)
		(duplicate_pad_numbers_are_jumpers no)
		(fp_line
			(start 0.635 0)
			(end -0.635 0)
			(stroke
				(width 0.508)
				(type default)
			)
			(layer "F.SilkS")
		)
		(fp_rect
			(start -0.9652 1.778)
			(end 0.9652 -1.778)
			(stroke
				(width 0)
				(type default)
			)
			(fill no)
			(layer "F.CrtYd")
		)
		(fp_poly
			(pts
				(xy -0.9652 -1.778) (xy 0.9652 -1.778) (xy 0.9652 1.778) (xy -0.9652 1.778)
			)
			(stroke
				(width 0)
				(type default)
			)
			(fill no)
			(layer "F.Fab")
		)
		(pad "1" smd rect
			(at 0 -0.9652 90)
			(size 1.397 1.143)
			(layers "F.Cu" "F.Mask" "F.Paste")
			(net "P5V_STBY")
		)
		(pad "2" smd rect
			(at 0 0.9652 90)
			(size 1.397 1.143)
			(layers "F.Cu" "F.Mask" "F.Paste")
			(net "GND")
		)
	)
	(footprint ""
		(layer "F.Cu")
		(at 215.392 -162.179 -90)
		(property "Reference" "C87"
			(at 0 0 270)
			(layer "F.SilkS")
			(hide yes)
			(effects
				(font
					(size 1.27 1.27)
				)
			)
		)
		(property "Value" "SCD1U16V2KX-3GP"
			(at 1.1811 -2.7051 270)
			(unlocked yes)
			(layer "F.Fab")
			(hide yes)
			(effects
				(font
					(size 1.016 1.016)
					(thickness 0.1524)
				)
			)
		)
		(property "Device Type" "C402H22"
			(at 1.1811 -4.2291 270)
			(unlocked yes)
			(layer "F.Fab")
			(hide yes)
			(effects
				(font
					(size 1.016 1.016)
					(thickness 0.1524)
				)
			)
		)
		(duplicate_pad_numbers_are_jumpers no)
		(fp_rect
			(start -0.4318 0.9525)
			(end 0.4318 -0.9525)
			(stroke
				(width 0)
				(type default)
			)
			(fill no)
			(layer "F.CrtYd")
		)
		(fp_rect
			(start -0.4318 0.9525)
			(end 0.4318 -0.9525)
			(stroke
				(width 0)
				(type default)
			)
			(fill no)
			(layer "F.Fab")
		)
		(pad "1" smd custom
			(at 0 -0.4445 270)
			(size 0.1524 0.1524)
			(layers "F.Cu" "F.Mask" "F.Paste")
			(net "P1V8_STBY")
			(options
				(clearance outline)
				(anchor circle)
			)
			(primitives
				(gr_poly
					(pts
						(arc
							(start 0.3048 -0.2032)
							(mid 0.275042 -0.275042)
							(end 0.2032 -0.3048)
						)
						(arc
							(start -0.2032 -0.3048)
							(mid -0.275042 -0.275042)
							(end -0.3048 -0.2032)
						)
						(arc
							(start -0.3048 0.2032)
							(mid -0.275042 0.275042)
							(end -0.2032 0.3048)
						)
						(arc
							(start 0.2032 0.3048)
							(mid 0.275042 0.275042)
							(end 0.3048 0.2032)
						)
					)
					(width 0)
					(fill yes)
				)
			)
		)
		(pad "2" smd custom
			(at 0 0.4445 270)
			(size 0.1524 0.1524)
			(layers "F.Cu" "F.Mask" "F.Paste")
			(net "GND")
			(options
				(clearance outline)
				(anchor circle)
			)
			(primitives
				(gr_poly
					(pts
						(arc
							(start 0.3048 -0.2032)
							(mid 0.275042 -0.275042)
							(end 0.2032 -0.3048)
						)
						(arc
							(start -0.2032 -0.3048)
							(mid -0.275042 -0.275042)
							(end -0.3048 -0.2032)
						)
						(arc
							(start -0.3048 0.2032)
							(mid -0.275042 0.275042)
							(end -0.2032 0.3048)
						)
						(arc
							(start 0.2032 0.3048)
							(mid 0.275042 0.275042)
							(end 0.3048 0.2032)
						)
					)
					(width 0)
					(fill yes)
				)
			)
		)
	)
	(footprint ""
		(layer "F.Cu")
		(at 79.62519 -62.705488)
		(property "Reference" "SR712"
			(at 0 0 0)
			(layer "F.SilkS")
			(hide yes)
			(effects
				(font
					(size 1.27 1.27)
				)
			)
		)
		(property "Value" "10R2F-L-GP"
			(at 0.064008 -3.993896 0)
			(unlocked yes)
			(layer "F.Fab")
			(hide yes)
			(effects
				(font
					(size 1.016 1.016)
					(thickness 0.1524)
				)
			)
		)
		(property "Device Type" "R402H14"
			(at 0.064008 -5.517896 0)
			(unlocked yes)
			(layer "F.Fab")
			(hide yes)
			(effects
				(font
					(size 1.016 1.016)
					(thickness 0.1524)
				)
			)
		)
		(duplicate_pad_numbers_are_jumpers no)
		(fp_line
			(start -0.508 -0.9398)
			(end -0.508 0.9398)
			(stroke
				(width 0.1524)
				(type default)
			)
			(layer "F.SilkS")
		)
		(fp_line
			(start 0.508 -0.9398)
			(end -0.508 -0.9398)
			(stroke
				(width 0.1524)
				(type default)
			)
			(layer "F.SilkS")
		)
		(fp_rect
			(start -0.508 0.9398)
			(end 0.508 -0.9398)
			(stroke
				(width 0)
				(type default)
			)
			(fill no)
			(layer "F.CrtYd")
		)
		(fp_rect
			(start -0.508 0.9398)
			(end 0.508 -0.9398)
			(stroke
				(width 0)
				(type default)
			)
			(fill no)
			(layer "F.Fab")
		)
		(pad "1" smd custom
			(at 0 -0.4445)
			(size 0.1397 0.1397)
			(layers "F.Cu" "F.Mask" "F.Paste")
			(net "P1V8_C")
			(options
				(clearance outline)
				(anchor circle)
			)
			(primitives
				(gr_poly
					(pts
						(arc
							(start -0.1778 -0.2794)
							(mid -0.249642 -0.249642)
							(end -0.2794 -0.1778)
						)
						(arc
							(start -0.2794 0.1778)
							(mid -0.249642 0.249642)
							(end -0.1778 0.2794)
						)
						(arc
							(start 0.1778 0.2794)
							(mid 0.249642 0.249642)
							(end 0.2794 0.1778)
						)
						(arc
							(start 0.2794 -0.1778)
							(mid 0.249642 -0.249642)
							(end 0.1778 -0.2794)
						)
					)
					(width 0)
					(fill yes)
				)
			)
		)
		(pad "2" smd custom
			(at 0 0.4445)
			(size 0.1397 0.1397)
			(layers "F.Cu" "F.Mask" "F.Paste")
			(net "SHELL_PLL_VDD")
			(options
				(clearance outline)
				(anchor circle)
			)
			(primitives
				(gr_poly
					(pts
						(arc
							(start -0.1778 -0.2794)
							(mid -0.249642 -0.249642)
							(end -0.2794 -0.1778)
						)
						(arc
							(start -0.2794 0.1778)
							(mid -0.249642 0.249642)
							(end -0.1778 0.2794)
						)
						(arc
							(start 0.1778 0.2794)
							(mid 0.249642 0.249642)
							(end 0.2794 0.1778)
						)
						(arc
							(start 0.2794 -0.1778)
							(mid 0.249642 -0.249642)
							(end 0.1778 -0.2794)
						)
					)
					(width 0)
					(fill yes)
				)
			)
		)
	)
	(footprint ""
		(layer "F.Cu")
		(at 303.320958 -61.595 -90)
		(property "Reference" "R206"
			(at 0 0 270)
			(layer "F.SilkS")
			(hide yes)
			(effects
				(font
					(size 1.27 1.27)
				)
			)
		)
		(property "Value" "0R2J-2-GP"
			(at 0.064008 -3.993896 270)
			(unlocked yes)
			(layer "F.Fab")
			(hide yes)
			(effects
				(font
					(size 1.016 1.016)
					(thickness 0.1524)
				)
			)
		)
		(property "Device Type" "R402H16"
			(at 0.064008 -5.517896 270)
			(unlocked yes)
			(layer "F.Fab")
			(hide yes)
			(effects
				(font
					(size 1.016 1.016)
					(thickness 0.1524)
				)
			)
		)
		(duplicate_pad_numbers_are_jumpers no)
		(fp_line
			(start -0.508 -0.9398)
			(end -0.508 0.9398)
			(stroke
				(width 0.1524)
				(type default)
			)
			(layer "F.SilkS")
		)
		(fp_line
			(start 0.508 -0.9398)
			(end -0.508 -0.9398)
			(stroke
				(width 0.1524)
				(type default)
			)
			(layer "F.SilkS")
		)
		(fp_rect
			(start -0.508 0.9398)
			(end 0.508 -0.9398)
			(stroke
				(width 0)
				(type default)
			)
			(fill no)
			(layer "F.CrtYd")
		)
		(fp_rect
			(start -0.508 0.9398)
			(end 0.508 -0.9398)
			(stroke
				(width 0)
				(type default)
			)
			(fill no)
			(layer "F.Fab")
		)
		(pad "1" smd custom
			(at 0 -0.4445 270)
			(size 0.1397 0.1397)
			(layers "F.Cu" "F.Mask" "F.Paste")
			(net "SAS_I2C_C_10G_SDA")
			(options
				(clearance outline)
				(anchor circle)
			)
			(primitives
				(gr_poly
					(pts
						(arc
							(start -0.1778 -0.2794)
							(mid -0.249642 -0.249642)
							(end -0.2794 -0.1778)
						)
						(arc
							(start -0.2794 0.1778)
							(mid -0.249642 0.249642)
							(end -0.1778 0.2794)
						)
						(arc
							(start 0.1778 0.2794)
							(mid 0.249642 0.249642)
							(end 0.2794 0.1778)
						)
						(arc
							(start 0.2794 -0.1778)
							(mid 0.249642 -0.249642)
							(end 0.1778 -0.2794)
						)
					)
					(width 0)
					(fill yes)
				)
			)
		)
		(pad "2" smd custom
			(at 0 0.4445 270)
			(size 0.1397 0.1397)
			(layers "F.Cu" "F.Mask" "F.Paste")
			(net "BMC_10G_SDA_2")
			(options
				(clearance outline)
				(anchor circle)
			)
			(primitives
				(gr_poly
					(pts
						(arc
							(start -0.1778 -0.2794)
							(mid -0.249642 -0.249642)
							(end -0.2794 -0.1778)
						)
						(arc
							(start -0.2794 0.1778)
							(mid -0.249642 0.249642)
							(end -0.1778 0.2794)
						)
						(arc
							(start 0.1778 0.2794)
							(mid 0.249642 0.249642)
							(end 0.2794 0.1778)
						)
						(arc
							(start 0.2794 -0.1778)
							(mid 0.249642 -0.249642)
							(end 0.1778 -0.2794)
						)
					)
					(width 0)
					(fill yes)
				)
			)
		)
	)
	(footprint ""
		(layer "F.Cu")
		(at 80.626966 -86.868 -90)
		(property "Reference" "SL12"
			(at 0 0 270)
			(layer "F.SilkS")
			(hide yes)
			(effects
				(font
					(size 1.27 1.27)
				)
			)
		)
		(property "Value" "MPZ2012S601AT-GP"
			(at 0 -4.2418 270)
			(unlocked yes)
			(layer "F.Fab")
			(hide yes)
			(effects
				(font
					(size 1.016 1.016)
					(thickness 0.1524)
				)
			)
		)
		(property "Device Type" "L805H42"
			(at 0 -5.7912 270)
			(unlocked yes)
			(layer "F.Fab")
			(hide yes)
			(effects
				(font
					(size 1.016 1.016)
					(thickness 0.1524)
				)
			)
		)
		(duplicate_pad_numbers_are_jumpers no)
		(fp_line
			(start -0.889 1.7018)
			(end -0.889 -1.7018)
			(stroke
				(width 0.1524)
				(type default)
			)
			(layer "F.SilkS")
		)
		(fp_line
			(start 0.889 1.7018)
			(end -0.889 1.7018)
			(stroke
				(width 0.1524)
				(type default)
			)
			(layer "F.SilkS")
		)
		(fp_line
			(start -0.889 -1.7018)
			(end 0.889 -1.7018)
			(stroke
				(width 0.1524)
				(type default)
			)
			(layer "F.SilkS")
		)
		(fp_line
			(start 0.889 -1.7018)
			(end 0.889 1.7018)
			(stroke
				(width 0.1524)
				(type default)
			)
			(layer "F.SilkS")
		)
		(fp_rect
			(start -0.9652 1.778)
			(end 0.9652 -1.778)
			(stroke
				(width 0)
				(type default)
			)
			(fill no)
			(layer "F.CrtYd")
		)
		(fp_rect
			(start -0.9652 1.778)
			(end 0.9652 -1.778)
			(stroke
				(width 0)
				(type default)
			)
			(fill no)
			(layer "F.Fab")
		)
		(pad "1" smd rect
			(at 0 -0.9652 270)
			(size 1.397 1.143)
			(layers "F.Cu" "F.Mask" "F.Paste")
			(net "SYSPLL_VDDA18")
		)
		(pad "2" smd rect
			(at 0 0.9652 270)
			(size 1.397 1.143)
			(layers "F.Cu" "F.Mask" "F.Paste")
			(net "P1V8_E")
		)
	)
	(footprint ""
		(layer "F.Cu")
		(at 53.975 -207.391 -90)
		(property "Reference" "R692"
			(at 0 0 270)
			(layer "F.SilkS")
			(hide yes)
			(effects
				(font
					(size 1.27 1.27)
				)
			)
		)
		(property "Value" "1K33R3F-GP"
			(at -0.0254 -2.5146 270)
			(unlocked yes)
			(layer "F.Fab")
			(hide yes)
			(effects
				(font
					(size 1.016 1.016)
					(thickness 0.1524)
				)
			)
		)
		(property "Device Type" "R603H22"
			(at -0.0254 -4.0386 270)
			(unlocked yes)
			(layer "F.Fab")
			(hide yes)
			(effects
				(font
					(size 1.016 1.016)
					(thickness 0.1524)
				)
			)
		)
		(duplicate_pad_numbers_are_jumpers no)
		(fp_line
			(start -0.4826 0)
			(end -0.2032 0)
			(stroke
				(width 0.2032)
				(type default)
			)
			(layer "F.SilkS")
		)
		(fp_line
			(start 0.2032 0)
			(end 0.4826 0)
			(stroke
				(width 0.2032)
				(type default)
			)
			(layer "F.SilkS")
		)
		(fp_rect
			(start -0.5842 1.3335)
			(end 0.5842 -1.3335)
			(stroke
				(width 0)
				(type default)
			)
			(fill no)
			(layer "F.CrtYd")
		)
		(fp_rect
			(start -0.5842 1.3335)
			(end 0.5842 -1.3335)
			(stroke
				(width 0)
				(type default)
			)
			(fill no)
			(layer "F.Fab")
		)
		(pad "1" smd custom
			(at 0 -0.762 270)
			(size 0.2159 0.2159)
			(layers "F.Cu" "F.Mask" "F.Paste")
			(net "MB0_HS_ENABLE")
			(options
				(clearance outline)
				(anchor circle)
			)
			(primitives
				(gr_poly
					(pts
						(arc
							(start -0.3302 -0.4318)
							(mid -0.402042 -0.402042)
							(end -0.4318 -0.3302)
						)
						(arc
							(start -0.4318 0.3302)
							(mid -0.402042 0.402042)
							(end -0.3302 0.4318)
						)
						(arc
							(start 0.3302 0.4318)
							(mid 0.402042 0.402042)
							(end 0.4318 0.3302)
						)
						(arc
							(start 0.4318 -0.3302)
							(mid 0.402042 -0.402042)
							(end 0.3302 -0.4318)
						)
					)
					(width 0)
					(fill yes)
				)
			)
		)
		(pad "2" smd custom
			(at 0 0.762 270)
			(size 0.2159 0.2159)
			(layers "F.Cu" "F.Mask" "F.Paste")
			(net "GND")
			(options
				(clearance outline)
				(anchor circle)
			)
			(primitives
				(gr_poly
					(pts
						(arc
							(start -0.3302 -0.4318)
							(mid -0.402042 -0.402042)
							(end -0.4318 -0.3302)
						)
						(arc
							(start -0.4318 0.3302)
							(mid -0.402042 0.402042)
							(end -0.3302 0.4318)
						)
						(arc
							(start 0.3302 0.4318)
							(mid 0.402042 0.402042)
							(end 0.4318 0.3302)
						)
						(arc
							(start 0.4318 -0.3302)
							(mid 0.402042 -0.402042)
							(end 0.3302 -0.4318)
						)
					)
					(width 0)
					(fill yes)
				)
			)
		)
	)
	(footprint ""
		(layer "F.Cu")
		(at 205.555596 -118.129812 90)
		(property "Reference" "PC224"
			(at 0 0 90)
			(layer "F.SilkS")
			(hide yes)
			(effects
				(font
					(size 1.27 1.27)
				)
			)
		)
		(property "Value" "SC1U16V3KX-5GP"
			(at 0 -2.8194 90)
			(unlocked yes)
			(layer "F.Fab")
			(hide yes)
			(effects
				(font
					(size 1.016 1.016)
					(thickness 0.1524)
				)
			)
		)
		(property "Device Type" "C603H36"
			(at 0 -4.3434 90)
			(unlocked yes)
			(layer "F.Fab")
			(hide yes)
			(effects
				(font
					(size 1.016 1.016)
					(thickness 0.1524)
				)
			)
		)
		(duplicate_pad_numbers_are_jumpers no)
		(fp_line
			(start 0.508 0)
			(end -0.508 0)
			(stroke
				(width 0.2032)
				(type default)
			)
			(layer "F.SilkS")
		)
		(fp_rect
			(start -0.5842 1.3335)
			(end 0.5842 -1.3335)
			(stroke
				(width 0)
				(type default)
			)
			(fill no)
			(layer "F.CrtYd")
		)
		(fp_rect
			(start -0.5842 1.3335)
			(end 0.5842 -1.3335)
			(stroke
				(width 0)
				(type default)
			)
			(fill no)
			(layer "F.Fab")
		)
		(pad "1" smd custom
			(at 0 -0.762 90)
			(size 0.2159 0.2159)
			(layers "F.Cu" "F.Mask" "F.Paste")
			(net "P1V5_E_VCC")
			(options
				(clearance outline)
				(anchor circle)
			)
			(primitives
				(gr_poly
					(pts
						(arc
							(start -0.3302 -0.4318)
							(mid -0.402042 -0.402042)
							(end -0.4318 -0.3302)
						)
						(arc
							(start -0.4318 0.3302)
							(mid -0.402042 0.402042)
							(end -0.3302 0.4318)
						)
						(arc
							(start 0.3302 0.4318)
							(mid 0.402042 0.402042)
							(end 0.4318 0.3302)
						)
						(arc
							(start 0.4318 -0.3302)
							(mid 0.402042 -0.402042)
							(end 0.3302 -0.4318)
						)
					)
					(width 0)
					(fill yes)
				)
			)
		)
		(pad "2" smd custom
			(at 0 0.762 90)
			(size 0.2159 0.2159)
			(layers "F.Cu" "F.Mask" "F.Paste")
			(net "AGND_P1V5_E")
			(options
				(clearance outline)
				(anchor circle)
			)
			(primitives
				(gr_poly
					(pts
						(arc
							(start -0.3302 -0.4318)
							(mid -0.402042 -0.402042)
							(end -0.4318 -0.3302)
						)
						(arc
							(start -0.4318 0.3302)
							(mid -0.402042 0.402042)
							(end -0.3302 0.4318)
						)
						(arc
							(start 0.3302 0.4318)
							(mid 0.402042 0.402042)
							(end 0.4318 0.3302)
						)
						(arc
							(start 0.4318 -0.3302)
							(mid 0.402042 -0.402042)
							(end 0.3302 -0.4318)
						)
					)
					(width 0)
					(fill yes)
				)
			)
		)
	)
	(footprint ""
		(layer "F.Cu")
		(at 337.312 -106.68 -90)
		(property "Reference" "PC12"
			(at 0 0 270)
			(layer "F.SilkS")
			(hide yes)
			(effects
				(font
					(size 1.27 1.27)
				)
			)
		)
		(property "Value" "SC2K2P50V3KX-GP"
			(at 0 -2.8194 270)
			(unlocked yes)
			(layer "F.Fab")
			(hide yes)
			(effects
				(font
					(size 1.016 1.016)
					(thickness 0.1524)
				)
			)
		)
		(property "Device Type" "C603"
			(at 0 -4.3434 270)
			(unlocked yes)
			(layer "F.Fab")
			(hide yes)
			(effects
				(font
					(size 1.016 1.016)
					(thickness 0.1524)
				)
			)
		)
		(duplicate_pad_numbers_are_jumpers no)
		(fp_line
			(start 0.508 0)
			(end -0.508 0)
			(stroke
				(width 0.2032)
				(type default)
			)
			(layer "F.SilkS")
		)
		(fp_rect
			(start -0.5842 1.3335)
			(end 0.5842 -1.3335)
			(stroke
				(width 0)
				(type default)
			)
			(fill no)
			(layer "F.CrtYd")
		)
		(fp_rect
			(start -0.5842 1.3335)
			(end 0.5842 -1.3335)
			(stroke
				(width 0)
				(type default)
			)
			(fill no)
			(layer "F.Fab")
		)
		(pad "1" smd custom
			(at 0 -0.762 270)
			(size 0.2159 0.2159)
			(layers "F.Cu" "F.Mask" "F.Paste")
			(net "P5V_STBY_SW")
			(options
				(clearance outline)
				(anchor circle)
			)
			(primitives
				(gr_poly
					(pts
						(arc
							(start -0.3302 -0.4318)
							(mid -0.402042 -0.402042)
							(end -0.4318 -0.3302)
						)
						(arc
							(start -0.4318 0.3302)
							(mid -0.402042 0.402042)
							(end -0.3302 0.4318)
						)
						(arc
							(start 0.3302 0.4318)
							(mid 0.402042 0.402042)
							(end 0.4318 0.3302)
						)
						(arc
							(start 0.4318 -0.3302)
							(mid 0.402042 -0.402042)
							(end 0.3302 -0.4318)
						)
					)
					(width 0)
					(fill yes)
				)
			)
		)
		(pad "2" smd custom
			(at 0 0.762 270)
			(size 0.2159 0.2159)
			(layers "F.Cu" "F.Mask" "F.Paste")
			(net "P5V_STBY__SNB")
			(options
				(clearance outline)
				(anchor circle)
			)
			(primitives
				(gr_poly
					(pts
						(arc
							(start -0.3302 -0.4318)
							(mid -0.402042 -0.402042)
							(end -0.4318 -0.3302)
						)
						(arc
							(start -0.4318 0.3302)
							(mid -0.402042 0.402042)
							(end -0.3302 0.4318)
						)
						(arc
							(start 0.3302 0.4318)
							(mid 0.402042 0.402042)
							(end 0.4318 0.3302)
						)
						(arc
							(start 0.4318 -0.3302)
							(mid 0.402042 -0.402042)
							(end 0.3302 -0.4318)
						)
					)
					(width 0)
					(fill yes)
				)
			)
		)
	)
)
